# S9S_MB_2U (Grand Teton) — schematic netlist excerpt (pin names and nets, part order shuffled) for the footprints in the layout excerpt that follows; sources: Cadence DE-HDL packaged netlist, KiCad conversion of 03242023_DA0F0TMBIJ0_F0T_Motherboard_J_brd_V01_OCP.brd

J28  SCONN288_ADR50017P087CC  SCONN288_ADR50017-P087CC IO  pkg DDR288S_1-1VXB  page 109
  VIN_BULK0  = P12V_S3_AUX_CPU1_NVDIMM
  RFU0  = TP_CHF_CPU1_DIMM2_FRU_0
  VIN_MGMT  = P3V3_AUX
  HSCL  = I3C_SPD_DDREFGH_CPU1_LVC1_SCL_3
  HSDA  = I3C_SPD_DDREFGH_CPU1_LVC1_SDA
  VSS0  = GND
  DQ0_A  = M_F_CPU1_SA_DQ<0>
  VSS1  = GND
  DQ1_A  = M_F_CPU1_SA_DQ<1>
  VSS2  = GND
  DQS0_A_T  = M_F_CPU1_SA_DQS_DP<0>
  DQS0_A_C  = M_F_CPU1_SA_DQS_DN<0>
  VSS3  = GND
  DQ4_A  = M_F_CPU1_SA_DQ<4>
  VSS4  = GND
  DQ5_A  = M_F_CPU1_SA_DQ<5>
  VSS5  = GND
  DQ8_A  = M_F_CPU1_SA_DQ<8>
  VSS6  = GND
  DQ9_A  = M_F_CPU1_SA_DQ<9>
  VSS7  = GND
  DQS1_A_T  = M_F_CPU1_SA_DQS_DP<1>
  DQS1_A_C  = M_F_CPU1_SA_DQS_DN<1>
  VSS8  = GND
  DQ12_A  = M_F_CPU1_SA_DQ<12>
  VSS9  = GND
  DQ13_A  = M_F_CPU1_SA_DQ<13>
  VSS10  = GND
  DQ16_A  = M_F_CPU1_SA_DQ<16>
  VSS11  = GND
  DQ17_A  = M_F_CPU1_SA_DQ<17>
  VSS12  = GND
  DQS2_A_T  = M_F_CPU1_SA_DQS_DP<2>
  DQS2_A_C  = M_F_CPU1_SA_DQS_DN<2>
  VSS13  = GND
  DQ20_A  = M_F_CPU1_SA_DQ<20>
  VSS14  = GND
  DQ21_A  = M_F_CPU1_SA_DQ<21>
  VSS15  = GND
  DQ24_A  = M_F_CPU1_SA_DQ<24>
  VSS16  = GND
  DQ25_A  = M_F_CPU1_SA_DQ<25>
  VSS17  = GND
  DQS3_A_T  = M_F_CPU1_SA_DQS_DP<3>
  DQS3_A_C  = M_F_CPU1_SA_DQS_DN<3>
  VSS18  = GND
  DQ28_A  = M_F_CPU1_SA_DQ<28>
  VSS19  = GND
  DQ29_A  = M_F_CPU1_SA_DQ<29>
  VSS20  = GND
  CB0_A  = M_F_CPU1_SA_CB<0>
  VSS21  = GND
  CB1_A  = M_F_CPU1_SA_CB<1>
  VSS22  = GND
  DQS4_A_T  = M_F_CPU1_SA_DQS_DP<4>
  DQS4_A_C  = M_F_CPU1_SA_DQS_DN<4>
  VSS23  = GND
  CB4_A  = M_F_CPU1_SA_CB<4>
  VSS24  = GND
  CB5_A  = M_F_CPU1_SA_CB<5>
  VSS25  = GND
  ALERT_N  = M_F_CPU1_ALERT_N
  VSS26  = GND
  CS0_A_N  = M_F_CPU1_SA_CS_N<2>
  VSS27  = GND
  CA0_A  = M_F_CPU1_SA_CA<0>
  VSS28  = GND
  CA2_A  = M_F_CPU1_SA_CA<2>
  VSS29  = GND
  CA4_A  = M_F_CPU1_SA_CA<4>
  VSS30  = GND
  CA6_A  = M_F_CPU1_SA_CA<6>
  VSS31  = GND
  PAR_A  = M_F_CPU1_SA_PAR
  VSS32  = GND
  CA0_B  = M_F_CPU1_SB_CA<0>
  VSS33  = GND
  CA2_B  = M_F_CPU1_SB_CA<2>
  VSS34  = GND
  CA4_B  = M_F_CPU1_SB_CA<4>
  VSS35  = GND
  CA6_B  = M_F_CPU1_SB_CA<6>
  VSS36  = GND
  CS0_B_N  = M_F_CPU1_SB_CS_N<2>
  VSS37  = GND
  \lbd||rsp_a_n\  = M_F_CPU1_SA_RSP<1>
  \lbs||rsp_b_n\  = M_F_CPU1_SB_RSP<1>
  VSS38  = GND
  CB4_B  = M_F_CPU1_SB_CB<4>
  VSS39  = GND
  CB5_B  = M_F_CPU1_SB_CB<5>
  VSS40  = GND
  \dqs9_b_t||tdqs9_b_t||dbi4_b_n\  = M_F_CPU1_SB_DQS_DP<9>
  \dqs9_b_c||tdqs9_b_c\  = M_F_CPU1_SB_DQS_DN<9>
  VSS41  = GND
  CB0_B  = M_F_CPU1_SB_CB<0>
  VSS42  = GND
  CB1_B  = M_F_CPU1_SB_CB<1>
  VSS43  = GND
  DQ0_B  = M_F_CPU1_SB_DQ<0>
  VSS44  = GND
  DQ1_B  = M_F_CPU1_SB_DQ<1>
  VSS45  = GND
  DQS0_B_T  = M_F_CPU1_SB_DQS_DP<0>
  DQS0_B_C  = M_F_CPU1_SB_DQS_DN<0>
  VSS46  = GND
  DQ4_B  = M_F_CPU1_SB_DQ<4>
  VSS47  = GND
  DQ5_B  = M_F_CPU1_SB_DQ<5>
  VSS48  = GND
  DQ8_B  = M_F_CPU1_SB_DQ<8>
  VSS49  = GND
  DQ9_B  = M_F_CPU1_SB_DQ<9>
  VSS50  = GND
  DQS1_B_T  = M_F_CPU1_SB_DQS_DP<1>
  DQS1_B_C  = M_F_CPU1_SB_DQS_DN<1>
  VSS51  = GND
  DQ12_B  = M_F_CPU1_SB_DQ<12>
  VSS52  = GND
  DQ13_B  = M_F_CPU1_SB_DQ<13>
  VSS53  = GND
  DQ16_B  = M_F_CPU1_SB_DQ<16>
  VSS54  = GND
  DQ17_B  = M_F_CPU1_SB_DQ<17>
  VSS55  = GND
  DQS2_B_T  = M_F_CPU1_SB_DQS_DP<2>
  DQS2_B_C  = M_F_CPU1_SB_DQS_DN<2>
  VSS56  = GND
  DQ20_B  = M_F_CPU1_SB_DQ<20>
  VSS57  = GND
  DQ21_B  = M_F_CPU1_SB_DQ<21>
  VSS58  = GND
  DQ24_B  = M_F_CPU1_SB_DQ<24>
  VSS59  = GND
  DQ25_B  = M_F_CPU1_SB_DQ<25>
  VSS60  = GND
  DQS3_B_T  = M_F_CPU1_SB_DQS_DP<3>
  DQS3_B_C  = M_F_CPU1_SB_DQS_DN<3>
  VSS61  = GND
  DQ28_B  = M_F_CPU1_SB_DQ<28>
  VSS62  = GND
  DQ29_B  = M_F_CPU1_SB_DQ<29>
  VSS63  = GND
  RFU1  = TP_CHF_CPU1_DIMM2_FRU_1
  VIN_BULK1  = P12V_S3_AUX_CPU1_NVDIMM
  VIN_BULK2  = P12V_S3_AUX_CPU1_NVDIMM
  \pwr_good||fail_n\  = PWRGD_CHF_CPU1_DIMM2
  HSA  = PD_CHF_CPU1_DIMM2_SAA
  RFU2  = TP_CHF_CPU1_DIMM2_FRU_2
  RFU3  = TP_CHF_CPU1_DIMM2_FRU_3
  VSS64  = GND
  DQ2_A  = M_F_CPU1_SA_DQ<2>
  VSS65  = GND
  DQ3_A  = M_F_CPU1_SA_DQ<3>
  VSS66  = GND
  \dqs5_a_c||tdqs5_a_c||dqs5_a_t||tdqs5_a_t\  = M_F_CPU1_SA_DQS_DN<5>
  \dqs5_a_t||tdqs5_a_t\  = M_F_CPU1_SA_DQS_DP<5>
  VSS67  = GND
  DQ6_A  = M_F_CPU1_SA_DQ<6>
  VSS68  = GND
  DQ7_A  = M_F_CPU1_SA_DQ<7>
  VSS69  = GND
  DQ10_A  = M_F_CPU1_SA_DQ<10>
  VSS70  = GND
  DQ11_A  = M_F_CPU1_SA_DQ<11>
  VSS71  = GND
  \dqs6_a_c||tdqs6_a_c||dqs6_a_t||tdqs6_a_t\  = M_F_CPU1_SA_DQS_DN<6>
  \dqs6_a_t||tdqs6_a_t\  = M_F_CPU1_SA_DQS_DP<6>
  VSS72  = GND
  DQ14_A  = M_F_CPU1_SA_DQ<14>
  VSS73  = GND
  DQ15_A  = M_F_CPU1_SA_DQ<15>
  VSS74  = GND
  DQ18_A  = M_F_CPU1_SA_DQ<18>
  VSS75  = GND
  DQ19_A  = M_F_CPU1_SA_DQ<19>
  VSS76  = GND
  \dqs7_a_c||tdqs7_a_c\  = M_F_CPU1_SA_DQS_DN<7>
  \dqs7_a_t||tdqs7_a_t\  = M_F_CPU1_SA_DQS_DP<7>
  VSS77  = GND
  DQ22_A  = M_F_CPU1_SA_DQ<22>
  VSS78  = GND
  DQ23_A  = M_F_CPU1_SA_DQ<23>
  VSS79  = GND
  DQ26_A  = M_F_CPU1_SA_DQ<26>
  VSS80  = GND
  DQ27_A  = M_F_CPU1_SA_DQ<27>
  VSS81  = GND
  \dqs8_a_c||tdqs8_a_c\  = M_F_CPU1_SA_DQS_DN<8>
  \dqs8_a_t||tdqs8_a_t\  = M_F_CPU1_SA_DQS_DP<8>
  VSS82  = GND
  DQ30_A  = M_F_CPU1_SA_DQ<30>
  VSS83  = GND
  DQ31_A  = M_F_CPU1_SA_DQ<31>
  VSS84  = GND
  CB2_A  = M_F_CPU1_SA_CB<2>
  VSS85  = GND
  CB3_A  = M_F_CPU1_SA_CB<3>
  VSS86  = GND
  \dqs9_a_c||tdqs9_a_c\  = M_F_CPU1_SA_DQS_DN<9>
  \dqs9_a_t||tdqs9_a_t\  = M_F_CPU1_SA_DQS_DP<9>
  VSS87  = GND
  CB6_A  = M_F_CPU1_SA_CB<6>
  VSS88  = GND
  CB7_A  = M_F_CPU1_SA_CB<7>
  VSS89  = GND
  RESET_N  = RST_M_EF_CPU1_FPGA_N
  VSS90  = GND
  CS1_A_N  = M_F_CPU1_SA_CS_N<3>
  VSS91  = GND
  CA1_A  = M_F_CPU1_SA_CA<1>
  VSS92  = GND
  CA3_A  = M_F_CPU1_SA_CA<3>
  VSS93  = GND
  CA5_A  = M_F_CPU1_SA_CA<5>
  VSS94  = GND
  CK_T  = M_F_CPU1_CLK_DP<1>
  CK_C  = M_F_CPU1_CLK_DN<1>
  VSS95  = GND
  RFU4  = TP_CHF_CPU1_DIMM2_FRU_4
  CA1_B  = M_F_CPU1_SB_CA<1>
  VSS96  = GND
  CA3_B  = M_F_CPU1_SB_CA<3>
  VSS97  = GND
  CA5_B  = M_F_CPU1_SB_CA<5>
  VSS98  = GND
  PAR_B  = M_F_CPU1_SB_PAR
  VSS99  = GND
  CS1_B_N  = M_F_CPU1_SB_CS_N<3>
  VSS100  = GND
  RFU5  = TP_CHF_CPU1_DIMM2_FRU_5
  RFU6  = TP_CHF_CPU1_DIMM2_FRU_6
  VSS101  = GND
  CB6_B  = M_F_CPU1_SB_CB<6>
  VSS102  = GND
  CB7_B  = M_F_CPU1_SB_CB<7>
  VSS103  = GND
  DQS4_B_C  = M_F_CPU1_SB_DQS_DN<4>
  DQS4_B_T  = M_F_CPU1_SB_DQS_DP<4>
  VSS104  = GND
  CB2_B  = M_F_CPU1_SB_CB<2>
  VSS105  = GND
  CB3_B  = M_F_CPU1_SB_CB<3>
  VSS106  = GND
  DQ2_B  = M_F_CPU1_SB_DQ<2>
  VSS107  = GND
  DQ3_B  = M_F_CPU1_SB_DQ<3>
  VSS108  = GND
  \dqs5_b_c||tdqs5_b_c\  = M_F_CPU1_SB_DQS_DN<5>
  \dqs5_b_t||tdqs5_b_t\  = M_F_CPU1_SB_DQS_DP<5>
  VSS109  = GND
  DQ6_B  = M_F_CPU1_SB_DQ<6>
  VSS110  = GND
  DQ7_B  = M_F_CPU1_SB_DQ<7>
  VSS111  = GND
  DQ10_B  = M_F_CPU1_SB_DQ<10>
  VSS112  = GND
  DQ11_B  = M_F_CPU1_SB_DQ<11>
  VSS113  = GND
  \dqs6_b_c||tdqs6_b_c\  = M_F_CPU1_SB_DQS_DN<6>
  \dqs6_b_t||tdqs6_b_t\  = M_F_CPU1_SB_DQS_DP<6>
  VSS114  = GND
  DQ14_B  = M_F_CPU1_SB_DQ<14>
  VSS115  = GND
  DQ15_B  = M_F_CPU1_SB_DQ<15>
  VSS116  = GND
  DQ18_B  = M_F_CPU1_SB_DQ<18>
  VSS117  = GND
  DQ19_B  = M_F_CPU1_SB_DQ<19>
  VSS118  = GND
  \dqs7_b_c||tdqs7_b_c\  = M_F_CPU1_SB_DQS_DN<7>
  \dqs7_b_t||tdqs7_b_t\  = M_F_CPU1_SB_DQS_DP<7>
  VSS119  = GND
  DQ22_B  = M_F_CPU1_SB_DQ<22>
  VSS120  = GND
  DQ23_B  = M_F_CPU1_SB_DQ<23>
  VSS121  = GND
  DQ26_B  = M_F_CPU1_SB_DQ<26>
  VSS122  = GND
  DQ27_B  = M_F_CPU1_SB_DQ<27>
  VSS123  = GND
  \dqs8_b_c||tdqs8_b_c\  = M_F_CPU1_SB_DQS_DN<8>
  \dqs8_b_t||tdqs8_b_t\  = M_F_CPU1_SB_DQS_DP<8>
  VSS124  = GND
  DQ30_B  = M_F_CPU1_SB_DQ<30>
  VSS125  = GND
  DQ31_B  = M_F_CPU1_SB_DQ<31>
  VSS126  = GND
  G1  = GND
  G2  = GND
  G3  = GND

(kicad_pcb
	(version 20260206)
	(generator "pcbnew")
	(generator_version "10.0")
	(general
		(thickness 1.6)
		(legacy_teardrops no)
	)
	(paper "A4")
	(title_block
		(title "03242023_DA0F0TMBIJ0_F0T_Motherboard_J_brd_V01_OCP.brd")
		(comment 1 "Grand Teton / footprint 3431 of 6105 (J28), pads 275-291 of 291")
	)
	(layers
		(0 "F.Cu" signal "TOP")
		(4 "In1.Cu" signal "GND")
		(6 "In2.Cu" signal "IN1")
		(8 "In3.Cu" signal "GND1")
		(10 "In4.Cu" signal "IN2")
		(12 "In5.Cu" signal "GND2")
		(14 "In6.Cu" signal "IN3")
		(16 "In7.Cu" signal "GND3")
		(18 "In8.Cu" signal "VCC")
		(20 "In9.Cu" signal "VCC1")
		(22 "In10.Cu" signal "GND4")
		(24 "In11.Cu" signal "IN4")
		(26 "In12.Cu" signal "GND5")
		(28 "In13.Cu" signal "IN5")
		(30 "In14.Cu" signal "GND6")
		(32 "In15.Cu" signal "IN6")
		(34 "In16.Cu" signal "GND7")
		(2 "B.Cu" signal "BOTTOM")
		(9 "F.Adhes" user "F.Adhesive")
		(11 "B.Adhes" user "B.Adhesive")
		(13 "F.Paste" user "Package Geometry/Pastemask Top")
		(15 "B.Paste" user "Package Geometry/Pastemask Bottom")
		(5 "F.SilkS" user "Ref Des/Silkscreen Top")
		(7 "B.SilkS" user "Ref Des/Silkscreen Bottom")
		(1 "F.Mask" user "Board Geometry/Soldermask Top")
		(3 "B.Mask" user "Board Geometry/Soldermask Bottom")
		(17 "Dwgs.User" user "User.Drawings")
		(19 "Cmts.User" user "User.Comments")
		(21 "Eco1.User" user "User.Eco1")
		(23 "Eco2.User" user "User.Eco2")
		(25 "Edge.Cuts" user "Board Geometry/Outline")
		(27 "Margin" user)
		(31 "F.CrtYd" user "Package Geometry/Place Bound Top")
		(29 "B.CrtYd" user "Package Geometry/Place Bound Bottom")
		(35 "F.Fab" user "Ref Des/Assembly Top")
		(33 "B.Fab" user "Ref Des/Assembly Bottom")
	)
	(footprint ""
		(layer "F.Cu")
		(at 175.95088 -258.091686)
		(property "Reference" "J28"
			(at -0.26924 -81.680812 0)
			(unlocked yes)
			(layer "F.SilkS")
			(effects
				(font
					(size 0.7874 0.5842)
					(thickness 0.1524)
				)
				(justify left)
			)
		)
		(property "Value" ""
			(at 0 0 0)
			(layer "F.Fab")
			(effects
				(font
					(size 1.27 1.27)
				)
			)
		)
		(duplicate_pad_numbers_are_jumpers no)
		(pad "275" smd rect
			(at 2.050034 52.274978 270)
			(size 0.519938 1.4986)
			(layers "F.Cu" "F.Mask" "F.Paste")
			(net "GND")
		)
		(pad "276" smd rect
			(at 2.050034 53.125116 270)
			(size 0.519938 1.4986)
			(layers "F.Cu" "F.Mask" "F.Paste")
			(net "M_F_CPU1_SB_DQ<23>")
		)
		(pad "277" smd rect
			(at 2.050034 53.975 270)
			(size 0.519938 1.4986)
			(layers "F.Cu" "F.Mask" "F.Paste")
			(net "GND")
		)
		(pad "278" smd rect
			(at 2.050034 54.824884 270)
			(size 0.519938 1.4986)
			(layers "F.Cu" "F.Mask" "F.Paste")
			(net "M_F_CPU1_SB_DQ<26>")
		)
		(pad "279" smd rect
			(at 2.050034 55.675022 270)
			(size 0.519938 1.4986)
			(layers "F.Cu" "F.Mask" "F.Paste")
			(net "GND")
		)
		(pad "280" smd rect
			(at 2.050034 56.524906 270)
			(size 0.519938 1.4986)
			(layers "F.Cu" "F.Mask" "F.Paste")
			(net "M_F_CPU1_SB_DQ<27>")
		)
		(pad "281" smd rect
			(at 2.050034 57.375044 270)
			(size 0.519938 1.4986)
			(layers "F.Cu" "F.Mask" "F.Paste")
			(net "GND")
		)
		(pad "282" smd rect
			(at 2.050034 58.224928 270)
			(size 0.519938 1.4986)
			(layers "F.Cu" "F.Mask" "F.Paste")
			(net "M_F_CPU1_SB_DQS_DN<8>")
		)
		(pad "283" smd rect
			(at 2.050034 59.075066 270)
			(size 0.519938 1.4986)
			(layers "F.Cu" "F.Mask" "F.Paste")
			(net "M_F_CPU1_SB_DQS_DP<8>")
		)
		(pad "284" smd rect
			(at 2.050034 59.92495 270)
			(size 0.519938 1.4986)
			(layers "F.Cu" "F.Mask" "F.Paste")
			(net "GND")
		)
		(pad "285" smd rect
			(at 2.050034 60.775088 270)
			(size 0.519938 1.4986)
			(layers "F.Cu" "F.Mask" "F.Paste")
			(net "M_F_CPU1_SB_DQ<30>")
		)
		(pad "286" smd rect
			(at 2.050034 61.624972 270)
			(size 0.519938 1.4986)
			(layers "F.Cu" "F.Mask" "F.Paste")
			(net "GND")
		)
		(pad "287" smd rect
			(at 2.050034 62.47511 270)
			(size 0.519938 1.4986)
			(layers "F.Cu" "F.Mask" "F.Paste")
			(net "M_F_CPU1_SB_DQ<31>")
		)
		(pad "288" smd rect
			(at 2.050034 63.324994 270)
			(size 0.519938 1.4986)
			(layers "F.Cu" "F.Mask" "F.Paste")
			(net "GND")
		)
		(pad "G1" thru_hole oval
			(at 0 -68.97497)
			(size 2.8194 1.5748)
			(drill oval 2.4384 1.1938)
			(layers "*.Cu" "*.Mask")
			(remove_unused_layers no)
			(net "GND")
			(clearance 0.127)
			(thermal_gap 0.127)
		)
		(pad "G2" thru_hole oval
			(at 0 3.875024)
			(size 2.8194 1.5748)
			(drill oval 2.4384 1.1938)
			(layers "*.Cu" "*.Mask")
			(remove_unused_layers no)
			(net "GND")
			(clearance 0.127)
			(thermal_gap 0.127)
		)
		(pad "G3" thru_hole oval
			(at 0 68.97497)
			(size 2.8194 1.5748)
			(drill oval 2.4384 1.1938)
			(layers "*.Cu" "*.Mask")
			(remove_unused_layers no)
			(net "GND")
			(clearance 0.127)
			(thermal_gap 0.127)
		)
	)
)
